# T6G (Grand Teton) — schematic netlist excerpt (pin names and nets, part order shuffled) for the footprints in the layout excerpt that follows; sources: Cadence DE-HDL packaged netlist, KiCad conversion of 04192023_DAF0TMB3IC0_F0TG_MB_C_brd_V02_OCP.brd

C43  Q_CAP  0.1UF 25V 10% X7R  pkg 0402  page 34 : A = P3V3_AUX ; B = GND
C5019  Q_CAP  1000PF 50V 5% X7R  pkg 0402  page 210 : A = GND ; B = PWRGD_PVDDCR_SOC_P1

(kicad_pcb
	(version 20260206)
	(generator "pcbnew")
	(generator_version "10.0")
	(general
		(thickness 1.6)
		(legacy_teardrops no)
	)
	(paper "A4")
	(title_block
		(title "04192023_DAF0TMB3IC0_F0TG_MB_C_brd_V02_OCP.brd")
		(comment 1 "Grand Teton / footprints 1688-1689 of 8354")
	)
	(layers
		(0 "F.Cu" signal "TOP")
		(4 "In1.Cu" signal "GND")
		(6 "In2.Cu" signal "IN1")
		(8 "In3.Cu" signal "GND1")
		(10 "In4.Cu" signal "IN2")
		(12 "In5.Cu" signal "GND2")
		(14 "In6.Cu" signal "IN3")
		(16 "In7.Cu" signal "GND3")
		(18 "In8.Cu" signal "VCC")
		(20 "In9.Cu" signal "VCC1")
		(22 "In10.Cu" signal "GND4")
		(24 "In11.Cu" signal "IN4")
		(26 "In12.Cu" signal "GND5")
		(28 "In13.Cu" signal "IN5")
		(30 "In14.Cu" signal "GND6")
		(32 "In15.Cu" signal "IN6")
		(34 "In16.Cu" signal "GND7")
		(2 "B.Cu" signal "BOTTOM")
		(9 "F.Adhes" user "F.Adhesive")
		(11 "B.Adhes" user "B.Adhesive")
		(13 "F.Paste" user "Package Geometry/Pastemask Top")
		(15 "B.Paste" user "Package Geometry/Pastemask Bottom")
		(5 "F.SilkS" user "Ref Des/Silkscreen Top")
		(7 "B.SilkS" user "Ref Des/Silkscreen Bottom")
		(1 "F.Mask" user "Board Geometry/Soldermask Top")
		(3 "B.Mask" user "Board Geometry/Soldermask Bottom")
		(17 "Dwgs.User" user "User.Drawings")
		(19 "Cmts.User" user "User.Comments")
		(21 "Eco1.User" user "User.Eco1")
		(23 "Eco2.User" user "User.Eco2")
		(25 "Edge.Cuts" user "Board Geometry/Outline")
		(27 "Margin" user)
		(31 "F.CrtYd" user "Package Geometry/Place Bound Top")
		(29 "B.CrtYd" user "Package Geometry/Place Bound Bottom")
		(35 "F.Fab" user "Ref Des/Assembly Top")
		(33 "B.Fab" user "Ref Des/Assembly Bottom")
	)
	(footprint ""
		(layer "F.Cu")
		(at 180.80863 -149.661118 -90)
		(property "Reference" "C43"
			(at 0 0 270)
			(layer "F.SilkS")
			(hide yes)
			(effects
				(font
					(size 1.27 1.27)
				)
			)
		)
		(property "Value" ""
			(at 0 0 270)
			(layer "F.Fab")
			(effects
				(font
					(size 1.27 1.27)
				)
			)
		)
		(duplicate_pad_numbers_are_jumpers no)
		(fp_line
			(start -0.7874 0.4064)
			(end -0.7874 -0.4064)
			(stroke
				(width 0.1524)
				(type default)
			)
			(layer "F.SilkS")
		)
		(fp_line
			(start 0.7874 0.4064)
			(end -0.7874 0.4064)
			(stroke
				(width 0.1524)
				(type default)
			)
			(layer "F.SilkS")
		)
		(fp_line
			(start -0.7874 -0.4064)
			(end 0.7874 -0.4064)
			(stroke
				(width 0.1524)
				(type default)
			)
			(layer "F.SilkS")
		)
		(fp_line
			(start 0.7874 -0.4064)
			(end 0.7874 0.4064)
			(stroke
				(width 0.1524)
				(type default)
			)
			(layer "F.SilkS")
		)
		(fp_line
			(start -0.67945 0.3048)
			(end -0.67945 -0.305054)
			(stroke
				(width 0.1)
				(type default)
			)
			(layer "F.Fab")
		)
		(fp_line
			(start -0.12065 0.3048)
			(end -0.67945 0.3048)
			(stroke
				(width 0.1)
				(type default)
			)
			(layer "F.Fab")
		)
		(fp_line
			(start 0.120396 0.3048)
			(end 0.120396 0.2794)
			(stroke
				(width 0.1)
				(type default)
			)
			(layer "F.Fab")
		)
		(fp_line
			(start 0.67945 0.3048)
			(end 0.120396 0.3048)
			(stroke
				(width 0.1)
				(type default)
			)
			(layer "F.Fab")
		)
		(fp_line
			(start -0.12065 0.2794)
			(end -0.12065 0.3048)
			(stroke
				(width 0.1)
				(type default)
			)
			(layer "F.Fab")
		)
		(fp_line
			(start 0.120396 0.2794)
			(end -0.12065 0.2794)
			(stroke
				(width 0.1)
				(type default)
			)
			(layer "F.Fab")
		)
		(fp_line
			(start -0.12065 -0.2794)
			(end 0.12065 -0.2794)
			(stroke
				(width 0.1)
				(type default)
			)
			(layer "F.Fab")
		)
		(fp_line
			(start 0.12065 -0.2794)
			(end 0.12065 -0.3048)
			(stroke
				(width 0.1)
				(type default)
			)
			(layer "F.Fab")
		)
		(fp_line
			(start 0.12065 -0.3048)
			(end 0.67945 -0.3048)
			(stroke
				(width 0.1)
				(type default)
			)
			(layer "F.Fab")
		)
		(fp_line
			(start 0.67945 -0.3048)
			(end 0.67945 0.3048)
			(stroke
				(width 0.1)
				(type default)
			)
			(layer "F.Fab")
		)
		(fp_line
			(start -0.67945 -0.305054)
			(end -0.12065 -0.305054)
			(stroke
				(width 0.1)
				(type default)
			)
			(layer "F.Fab")
		)
		(fp_line
			(start -0.12065 -0.305054)
			(end -0.12065 -0.2794)
			(stroke
				(width 0.1)
				(type default)
			)
			(layer "F.Fab")
		)
		(pad "1" smd circle
			(at -0.40005 0 270)
			(size 0 0)
			(layers "F.Cu" "F.Mask" "F.Paste")
			(net "P3V3_AUX")
		)
		(pad "2" smd circle
			(at 0.40005 0 270)
			(size 0 0)
			(layers "F.Cu" "F.Mask" "F.Paste")
			(net "GND")
		)
	)
	(footprint ""
		(layer "F.Cu")
		(at 88.431878 -145.50136 -90)
		(property "Reference" "C5019"
			(at 0 0 270)
			(layer "F.SilkS")
			(hide yes)
			(effects
				(font
					(size 1.27 1.27)
				)
			)
		)
		(property "Value" ""
			(at 0 0 270)
			(layer "F.Fab")
			(effects
				(font
					(size 1.27 1.27)
				)
			)
		)
		(duplicate_pad_numbers_are_jumpers no)
		(fp_line
			(start -0.7874 0.4064)
			(end -0.7874 -0.4064)
			(stroke
				(width 0.1524)
				(type default)
			)
			(layer "F.SilkS")
		)
		(fp_line
			(start 0.7874 0.4064)
			(end -0.7874 0.4064)
			(stroke
				(width 0.1524)
				(type default)
			)
			(layer "F.SilkS")
		)
		(fp_line
			(start -0.7874 -0.4064)
			(end 0.7874 -0.4064)
			(stroke
				(width 0.1524)
				(type default)
			)
			(layer "F.SilkS")
		)
		(fp_line
			(start 0.7874 -0.4064)
			(end 0.7874 0.4064)
			(stroke
				(width 0.1524)
				(type default)
			)
			(layer "F.SilkS")
		)
		(fp_line
			(start -0.67945 0.3048)
			(end -0.67945 -0.305054)
			(stroke
				(width 0.1)
				(type default)
			)
			(layer "F.Fab")
		)
		(fp_line
			(start -0.12065 0.3048)
			(end -0.67945 0.3048)
			(stroke
				(width 0.1)
				(type default)
			)
			(layer "F.Fab")
		)
		(fp_line
			(start 0.120396 0.3048)
			(end 0.120396 0.2794)
			(stroke
				(width 0.1)
				(type default)
			)
			(layer "F.Fab")
		)
		(fp_line
			(start 0.67945 0.3048)
			(end 0.120396 0.3048)
			(stroke
				(width 0.1)
				(type default)
			)
			(layer "F.Fab")
		)
		(fp_line
			(start -0.12065 0.2794)
			(end -0.12065 0.3048)
			(stroke
				(width 0.1)
				(type default)
			)
			(layer "F.Fab")
		)
		(fp_line
			(start 0.120396 0.2794)
			(end -0.12065 0.2794)
			(stroke
				(width 0.1)
				(type default)
			)
			(layer "F.Fab")
		)
		(fp_line
			(start -0.12065 -0.2794)
			(end 0.12065 -0.2794)
			(stroke
				(width 0.1)
				(type default)
			)
			(layer "F.Fab")
		)
		(fp_line
			(start 0.12065 -0.2794)
			(end 0.12065 -0.3048)
			(stroke
				(width 0.1)
				(type default)
			)
			(layer "F.Fab")
		)
		(fp_line
			(start 0.12065 -0.3048)
			(end 0.67945 -0.3048)
			(stroke
				(width 0.1)
				(type default)
			)
			(layer "F.Fab")
		)
		(fp_line
			(start 0.67945 -0.3048)
			(end 0.67945 0.3048)
			(stroke
				(width 0.1)
				(type default)
			)
			(layer "F.Fab")
		)
		(fp_line
			(start -0.67945 -0.305054)
			(end -0.12065 -0.305054)
			(stroke
				(width 0.1)
				(type default)
			)
			(layer "F.Fab")
		)
		(fp_line
			(start -0.12065 -0.305054)
			(end -0.12065 -0.2794)
			(stroke
				(width 0.1)
				(type default)
			)
			(layer "F.Fab")
		)
		(pad "1" smd circle
			(at -0.40005 0 270)
			(size 0 0)
			(layers "F.Cu" "F.Mask" "F.Paste")
			(net "GND")
		)
		(pad "2" smd circle
			(at 0.40005 0 270)
			(size 0 0)
			(layers "F.Cu" "F.Mask" "F.Paste")
			(net "PWRGD_PVDDCR_SOC_P1")
		)
	)
)
